# S9S_MB_2U (Grand Teton) — schematic netlist excerpt (pin names and nets, part order shuffled) for the footprints in the layout excerpt that follows; sources: Cadence DE-HDL packaged netlist, KiCad conversion of 03242023_DA0F0TMBIJ0_F0T_Motherboard_J_brd_V01_OCP.brd

R3430  Q_RES  100K 1% EMPTY  pkg 0402LF  page 147 : A = GPU_FPGA_OVERT_N ; B = GND
R4694  Q_RES  1K 1% CHIP  pkg 0402LF  page 167 : A = FM_P2E_BUF2_EQB1 ; B = GND

(kicad_pcb
	(version 20260206)
	(generator "pcbnew")
	(generator_version "10.0")
	(general
		(thickness 1.6)
		(legacy_teardrops no)
	)
	(paper "A4")
	(title_block
		(title "03242023_DA0F0TMBIJ0_F0T_Motherboard_J_brd_V01_OCP.brd")
		(comment 1 "Grand Teton / footprints 3769-3770 of 6105")
	)
	(layers
		(0 "F.Cu" signal "TOP")
		(4 "In1.Cu" signal "GND")
		(6 "In2.Cu" signal "IN1")
		(8 "In3.Cu" signal "GND1")
		(10 "In4.Cu" signal "IN2")
		(12 "In5.Cu" signal "GND2")
		(14 "In6.Cu" signal "IN3")
		(16 "In7.Cu" signal "GND3")
		(18 "In8.Cu" signal "VCC")
		(20 "In9.Cu" signal "VCC1")
		(22 "In10.Cu" signal "GND4")
		(24 "In11.Cu" signal "IN4")
		(26 "In12.Cu" signal "GND5")
		(28 "In13.Cu" signal "IN5")
		(30 "In14.Cu" signal "GND6")
		(32 "In15.Cu" signal "IN6")
		(34 "In16.Cu" signal "GND7")
		(2 "B.Cu" signal "BOTTOM")
		(9 "F.Adhes" user "F.Adhesive")
		(11 "B.Adhes" user "B.Adhesive")
		(13 "F.Paste" user "Package Geometry/Pastemask Top")
		(15 "B.Paste" user "Package Geometry/Pastemask Bottom")
		(5 "F.SilkS" user "Ref Des/Silkscreen Top")
		(7 "B.SilkS" user "Ref Des/Silkscreen Bottom")
		(1 "F.Mask" user "Board Geometry/Soldermask Top")
		(3 "B.Mask" user "Board Geometry/Soldermask Bottom")
		(17 "Dwgs.User" user "User.Drawings")
		(19 "Cmts.User" user "User.Comments")
		(21 "Eco1.User" user "User.Eco1")
		(23 "Eco2.User" user "User.Eco2")
		(25 "Edge.Cuts" user "Board Geometry/Outline")
		(27 "Margin" user)
		(31 "F.CrtYd" user "Package Geometry/Place Bound Top")
		(29 "B.CrtYd" user "Package Geometry/Place Bound Bottom")
		(35 "F.Fab" user "Ref Des/Assembly Top")
		(33 "B.Fab" user "Ref Des/Assembly Bottom")
	)
	(footprint ""
		(layer "F.Cu")
		(at 46.093634 -391.089642)
		(property "Reference" "R4694"
			(at 0 0 0)
			(layer "F.SilkS")
			(hide yes)
			(effects
				(font
					(size 1.27 1.27)
				)
			)
		)
		(property "Value" ""
			(at 0 0 0)
			(layer "F.Fab")
			(effects
				(font
					(size 1.27 1.27)
				)
			)
		)
		(duplicate_pad_numbers_are_jumpers no)
		(fp_line
			(start -0.7874 -0.4064)
			(end 0.7874 -0.4064)
			(stroke
				(width 0.1524)
				(type default)
			)
			(layer "F.SilkS")
		)
		(fp_line
			(start -0.7874 0.4064)
			(end -0.7874 -0.4064)
			(stroke
				(width 0.1524)
				(type default)
			)
			(layer "F.SilkS")
		)
		(fp_line
			(start 0.7874 -0.4064)
			(end 0.7874 0.4064)
			(stroke
				(width 0.1524)
				(type default)
			)
			(layer "F.SilkS")
		)
		(fp_line
			(start 0.7874 0.4064)
			(end -0.7874 0.4064)
			(stroke
				(width 0.1524)
				(type default)
			)
			(layer "F.SilkS")
		)
		(fp_line
			(start -0.67945 -0.305054)
			(end -0.12065 -0.305054)
			(stroke
				(width 0.1)
				(type default)
			)
			(layer "F.Fab")
		)
		(fp_line
			(start -0.67945 0.3048)
			(end -0.67945 -0.305054)
			(stroke
				(width 0.1)
				(type default)
			)
			(layer "F.Fab")
		)
		(fp_line
			(start -0.12065 -0.305054)
			(end -0.12065 -0.2794)
			(stroke
				(width 0.1)
				(type default)
			)
			(layer "F.Fab")
		)
		(fp_line
			(start -0.12065 -0.2794)
			(end 0.12065 -0.2794)
			(stroke
				(width 0.1)
				(type default)
			)
			(layer "F.Fab")
		)
		(fp_line
			(start -0.12065 0.2794)
			(end -0.12065 0.3048)
			(stroke
				(width 0.1)
				(type default)
			)
			(layer "F.Fab")
		)
		(fp_line
			(start -0.12065 0.3048)
			(end -0.67945 0.3048)
			(stroke
				(width 0.1)
				(type default)
			)
			(layer "F.Fab")
		)
		(fp_line
			(start 0.120396 0.2794)
			(end -0.12065 0.2794)
			(stroke
				(width 0.1)
				(type default)
			)
			(layer "F.Fab")
		)
		(fp_line
			(start 0.120396 0.3048)
			(end 0.120396 0.2794)
			(stroke
				(width 0.1)
				(type default)
			)
			(layer "F.Fab")
		)
		(fp_line
			(start 0.12065 -0.3048)
			(end 0.67945 -0.3048)
			(stroke
				(width 0.1)
				(type default)
			)
			(layer "F.Fab")
		)
		(fp_line
			(start 0.12065 -0.2794)
			(end 0.12065 -0.3048)
			(stroke
				(width 0.1)
				(type default)
			)
			(layer "F.Fab")
		)
		(fp_line
			(start 0.67945 -0.3048)
			(end 0.67945 0.3048)
			(stroke
				(width 0.1)
				(type default)
			)
			(layer "F.Fab")
		)
		(fp_line
			(start 0.67945 0.3048)
			(end 0.120396 0.3048)
			(stroke
				(width 0.1)
				(type default)
			)
			(layer "F.Fab")
		)
		(pad "1" smd circle
			(at -0.40005 0)
			(size 0 0)
			(layers "F.Cu" "F.Mask" "F.Paste")
			(net "FM_P2E_BUF2_EQB1")
		)
		(pad "2" smd circle
			(at 0.40005 0)
			(size 0 0)
			(layers "F.Cu" "F.Mask" "F.Paste")
			(net "GND")
		)
	)
	(footprint ""
		(layer "F.Cu")
		(at 424.223942 -397.651478 180)
		(property "Reference" "R3430"
			(at 0 0 180)
			(layer "F.SilkS")
			(hide yes)
			(effects
				(font
					(size 1.27 1.27)
				)
			)
		)
		(property "Value" ""
			(at 0 0 180)
			(layer "F.Fab")
			(effects
				(font
					(size 1.27 1.27)
				)
			)
		)
		(duplicate_pad_numbers_are_jumpers no)
		(fp_line
			(start 0.7874 0.4064)
			(end -0.7874 0.4064)
			(stroke
				(width 0.1524)
				(type default)
			)
			(layer "F.SilkS")
		)
		(fp_line
			(start 0.7874 -0.4064)
			(end 0.7874 0.4064)
			(stroke
				(width 0.1524)
				(type default)
			)
			(layer "F.SilkS")
		)
		(fp_line
			(start -0.7874 0.4064)
			(end -0.7874 -0.4064)
			(stroke
				(width 0.1524)
				(type default)
			)
			(layer "F.SilkS")
		)
		(fp_line
			(start -0.7874 -0.4064)
			(end 0.7874 -0.4064)
			(stroke
				(width 0.1524)
				(type default)
			)
			(layer "F.SilkS")
		)
		(fp_line
			(start 0.67945 0.3048)
			(end 0.120396 0.3048)
			(stroke
				(width 0.1)
				(type default)
			)
			(layer "F.Fab")
		)
		(fp_line
			(start 0.67945 -0.3048)
			(end 0.67945 0.3048)
			(stroke
				(width 0.1)
				(type default)
			)
			(layer "F.Fab")
		)
		(fp_line
			(start 0.12065 -0.2794)
			(end 0.12065 -0.3048)
			(stroke
				(width 0.1)
				(type default)
			)
			(layer "F.Fab")
		)
		(fp_line
			(start 0.12065 -0.3048)
			(end 0.67945 -0.3048)
			(stroke
				(width 0.1)
				(type default)
			)
			(layer "F.Fab")
		)
		(fp_line
			(start 0.120396 0.3048)
			(end 0.120396 0.2794)
			(stroke
				(width 0.1)
				(type default)
			)
			(layer "F.Fab")
		)
		(fp_line
			(start 0.120396 0.2794)
			(end -0.12065 0.2794)
			(stroke
				(width 0.1)
				(type default)
			)
			(layer "F.Fab")
		)
		(fp_line
			(start -0.12065 0.3048)
			(end -0.67945 0.3048)
			(stroke
				(width 0.1)
				(type default)
			)
			(layer "F.Fab")
		)
		(fp_line
			(start -0.12065 0.2794)
			(end -0.12065 0.3048)
			(stroke
				(width 0.1)
				(type default)
			)
			(layer "F.Fab")
		)
		(fp_line
			(start -0.12065 -0.2794)
			(end 0.12065 -0.2794)
			(stroke
				(width 0.1)
				(type default)
			)
			(layer "F.Fab")
		)
		(fp_line
			(start -0.12065 -0.305054)
			(end -0.12065 -0.2794)
			(stroke
				(width 0.1)
				(type default)
			)
			(layer "F.Fab")
		)
		(fp_line
			(start -0.67945 0.3048)
			(end -0.67945 -0.305054)
			(stroke
				(width 0.1)
				(type default)
			)
			(layer "F.Fab")
		)
		(fp_line
			(start -0.67945 -0.305054)
			(end -0.12065 -0.305054)
			(stroke
				(width 0.1)
				(type default)
			)
			(layer "F.Fab")
		)
		(pad "1" smd circle
			(at -0.40005 0 180)
			(size 0 0)
			(layers "F.Cu" "F.Mask" "F.Paste")
			(net "GPU_FPGA_OVERT_N")
		)
		(pad "2" smd circle
			(at 0.40005 0 180)
			(size 0 0)
			(layers "F.Cu" "F.Mask" "F.Paste")
			(net "GND")
		)
	)
)
